(kicad_pcb
	(version 20260206)
	(generator "pcbnew")
	(generator_version "10.0")
	(general
		(thickness 1.6)
		(legacy_teardrops no)
	)
	(paper "A4")
	(title_block
		(title "12092022_DA0F0TMDCD0_F0T_Management_Board_D_brd_V3_OCP.brd")
		(comment 1 "Grand Teton / footprint 162 of 1440 (U25), pads 1-112 of 256")
	)
	(layers
		(0 "F.Cu" signal "TOP")
		(4 "In1.Cu" signal "GND")
		(6 "In2.Cu" signal "IN1")
		(8 "In3.Cu" signal "GND1")
		(10 "In4.Cu" signal "IN2")
		(12 "In5.Cu" signal "VCC")
		(14 "In6.Cu" signal "VCC1")
		(16 "In7.Cu" signal "IN3")
		(18 "In8.Cu" signal "GND2")
		(20 "In9.Cu" signal "IN4")
		(22 "In10.Cu" signal "GND3")
		(2 "B.Cu" signal "BOTTOM")
		(9 "F.Adhes" user "F.Adhesive")
		(11 "B.Adhes" user "B.Adhesive")
		(13 "F.Paste" user "Package Geometry/Pastemask Top")
		(15 "B.Paste" user "Package Geometry/Pastemask Bottom")
		(5 "F.SilkS" user "Ref Des/Silkscreen Top")
		(7 "B.SilkS" user "Ref Des/Silkscreen Bottom")
		(1 "F.Mask" user "Board Geometry/Soldermask Top")
		(3 "B.Mask" user "Board Geometry/Soldermask Bottom")
		(17 "Dwgs.User" user "User.Drawings")
		(19 "Cmts.User" user "User.Comments")
		(21 "Eco1.User" user "User.Eco1")
		(23 "Eco2.User" user "User.Eco2")
		(25 "Edge.Cuts" user "Board Geometry/Outline")
		(27 "Margin" user)
		(31 "F.CrtYd" user "Package Geometry/Place Bound Top")
		(29 "B.CrtYd" user "Package Geometry/Place Bound Bottom")
		(35 "F.Fab" user "Ref Des/Assembly Top")
		(33 "B.Fab" user "Ref Des/Assembly Bottom")
	)
	(footprint ""
		(layer "F.Cu")
		(at 21.459444 -93.587062 180)
		(property "Reference" "U25"
			(at -10.595356 -8.218932 0)
			(unlocked yes)
			(layer "F.SilkS")
			(effects
				(font
					(size 0.7874 0.5842)
					(thickness 0.1524)
				)
				(justify left)
			)
		)
		(property "Value" ""
			(at 0 0 180)
			(layer "F.Fab")
			(effects
				(font
					(size 1.27 1.27)
				)
			)
		)
		(duplicate_pad_numbers_are_jumpers no)
		(pad "A1" smd circle
			(at -5.999988 -5.999988 180)
			(size 0.4064 0.4064)
			(layers "F.Cu" "F.Mask" "F.Paste")
			(net "PVCCA_AUX_PLD")
		)
		(pad "A2" smd circle
			(at -5.199888 -5.999988 180)
			(size 0.4064 0.4064)
			(layers "F.Cu" "F.Mask" "F.Paste")
			(net "Net_316")
		)
		(pad "A3" smd circle
			(at -4.400042 -5.999988 180)
			(size 0.4064 0.4064)
			(layers "F.Cu" "F.Mask" "F.Paste")
			(net "BSM_PRSNT_R1_N")
		)
		(pad "A4" smd circle
			(at -3.599942 -5.999988 180)
			(size 0.4064 0.4064)
			(layers "F.Cu" "F.Mask" "F.Paste")
			(net "RST_PLTRST_R1_N")
		)
		(pad "A5" smd circle
			(at -2.800096 -5.999988 180)
			(size 0.4064 0.4064)
			(layers "F.Cu" "F.Mask" "F.Paste")
			(net "RST_RSMRST_N")
		)
		(pad "A6" smd circle
			(at -1.999996 -5.999988 180)
			(size 0.4064 0.4064)
			(layers "F.Cu" "F.Mask" "F.Paste")
			(net "JTAG_SCM_PLD_TDI")
		)
		(pad "A7" smd circle
			(at -1.199896 -5.999988 180)
			(size 0.4064 0.4064)
			(layers "F.Cu" "F.Mask" "F.Paste")
			(net "JTAG_SCM_PLD_TCK")
		)
		(pad "A8" smd circle
			(at -0.40005 -5.999988 180)
			(size 0.4064 0.4064)
			(layers "F.Cu" "F.Mask" "F.Paste")
			(net "IRQ_BMC_PCH_NMI_R_N")
		)
		(pad "A9" smd circle
			(at 0.40005 -5.999988 180)
			(size 0.4064 0.4064)
			(layers "F.Cu" "F.Mask" "F.Paste")
			(net "SMB_BMC_MM16_R3_SCL")
		)
		(pad "A10" smd circle
			(at 1.199896 -5.999988 180)
			(size 0.4064 0.4064)
			(layers "F.Cu" "F.Mask" "F.Paste")
			(net "Net_75")
		)
		(pad "A11" smd circle
			(at 1.999996 -5.999988 180)
			(size 0.4064 0.4064)
			(layers "F.Cu" "F.Mask" "F.Paste")
			(net "RST_EXTRST_R_N")
		)
		(pad "A12" smd circle
			(at 2.800096 -5.999988 180)
			(size 0.4064 0.4064)
			(layers "F.Cu" "F.Mask" "F.Paste")
			(net "FM_ADR_COMPLETE")
		)
		(pad "A13" smd circle
			(at 3.599942 -5.999988 180)
			(size 0.4064 0.4064)
			(layers "F.Cu" "F.Mask" "F.Paste")
			(net "PU_FPGA_NSTATUS")
		)
		(pad "A14" smd circle
			(at 4.400042 -5.999988 180)
			(size 0.4064 0.4064)
			(layers "F.Cu" "F.Mask" "F.Paste")
			(net "SGPIO_CLK_PLD_0")
		)
		(pad "A15" smd circle
			(at 5.199888 -5.999988 180)
			(size 0.4064 0.4064)
			(layers "F.Cu" "F.Mask" "F.Paste")
			(net "FM_THERMTRIP_DLY_LVC1_R_N")
		)
		(pad "A16" smd circle
			(at 5.999988 -5.999988 180)
			(size 0.4064 0.4064)
			(layers "F.Cu" "F.Mask" "F.Paste")
			(net "PVCCA_AUX_PLD")
		)
		(pad "B1" smd circle
			(at -5.999988 -5.199888 180)
			(size 0.4064 0.4064)
			(layers "F.Cu" "F.Mask" "F.Paste")
			(net "Net_298")
		)
		(pad "B2" smd circle
			(at -5.199888 -5.199888 180)
			(size 0.4064 0.4064)
			(layers "F.Cu" "F.Mask" "F.Paste")
			(net "GND")
		)
		(pad "B3" smd circle
			(at -4.400042 -5.199888 180)
			(size 0.4064 0.4064)
			(layers "F.Cu" "F.Mask" "F.Paste")
			(net "IRQ_BMC_CPU_NMI_R")
		)
		(pad "B4" smd circle
			(at -3.599942 -5.199888 180)
			(size 0.4064 0.4064)
			(layers "F.Cu" "F.Mask" "F.Paste")
			(net "RST_PCA9548_SENSOR_N")
		)
		(pad "B5" smd circle
			(at -2.800096 -5.199888 180)
			(size 0.4064 0.4064)
			(layers "F.Cu" "F.Mask" "F.Paste")
			(net "FM_TPM_PRSNT_1_R_N")
		)
		(pad "B6" smd circle
			(at -1.999996 -5.199888 180)
			(size 0.4064 0.4064)
			(layers "F.Cu" "F.Mask" "F.Paste")
			(net "FM_JTAG_BMC_MUX_SEL_R2")
		)
		(pad "B7" smd circle
			(at -1.199896 -5.199888 180)
			(size 0.4064 0.4064)
			(layers "F.Cu" "F.Mask" "F.Paste")
			(net "IRQ_UV_DETECT_N")
		)
		(pad "B8" smd circle
			(at -0.40005 -5.199888 180)
			(size 0.4064 0.4064)
			(layers "F.Cu" "F.Mask" "F.Paste")
			(net "JTAG_SCM_PLD_TMS")
		)
		(pad "B9" smd circle
			(at 0.40005 -5.199888 180)
			(size 0.4064 0.4064)
			(layers "F.Cu" "F.Mask" "F.Paste")
			(net "IRQ_PCH_SCI_WHEA_N")
		)
		(pad "B10" smd circle
			(at 1.199896 -5.199888 180)
			(size 0.4064 0.4064)
			(layers "F.Cu" "F.Mask" "F.Paste")
			(net "PU_PT20D")
		)
		(pad "B11" smd circle
			(at 1.999996 -5.199888 180)
			(size 0.4064 0.4064)
			(layers "F.Cu" "F.Mask" "F.Paste")
			(net "IRQ_OC_DETECT_N")
		)
		(pad "B12" smd circle
			(at 2.800096 -5.199888 180)
			(size 0.4064 0.4064)
			(layers "F.Cu" "F.Mask" "F.Paste")
			(net "SGPIO_PLD_LD_0")
		)
		(pad "B13" smd circle
			(at 3.599942 -5.199888 180)
			(size 0.4064 0.4064)
			(layers "F.Cu" "F.Mask" "F.Paste")
			(net "IRQ_OC_DETECT_EN_N")
		)
		(pad "B14" smd circle
			(at 4.400042 -5.199888 180)
			(size 0.4064 0.4064)
			(layers "F.Cu" "F.Mask" "F.Paste")
			(net "SGPIO_PLD_DI_0")
		)
		(pad "B15" smd circle
			(at 5.199888 -5.199888 180)
			(size 0.4064 0.4064)
			(layers "F.Cu" "F.Mask" "F.Paste")
			(net "GND")
		)
		(pad "B16" smd circle
			(at 5.999988 -5.199888 180)
			(size 0.4064 0.4064)
			(layers "F.Cu" "F.Mask" "F.Paste")
			(net "FM_PECI_SEL_N")
		)
		(pad "C1" smd circle
			(at -5.999988 -4.400042 180)
			(size 0.4064 0.4064)
			(layers "F.Cu" "F.Mask" "F.Paste")
			(net "Net_302")
		)
		(pad "C2" smd circle
			(at -5.199888 -4.400042 180)
			(size 0.4064 0.4064)
			(layers "F.Cu" "F.Mask" "F.Paste")
			(net "Net_299")
		)
		(pad "C3" smd circle
			(at -4.400042 -4.400042 180)
			(size 0.4064 0.4064)
			(layers "F.Cu" "F.Mask" "F.Paste")
			(net "GND")
		)
		(pad "C4" smd circle
			(at -3.599942 -4.400042 180)
			(size 0.4064 0.4064)
			(layers "F.Cu" "F.Mask" "F.Paste")
			(net "FM_TPM_PRSNT_0_R_N")
		)
		(pad "C5" smd circle
			(at -2.800096 -4.400042 180)
			(size 0.4064 0.4064)
			(layers "F.Cu" "F.Mask" "F.Paste")
			(net "PWRGD_PSU_AC_PWROK_PLD")
		)
		(pad "C6" smd circle
			(at -1.999996 -4.400042 180)
			(size 0.4064 0.4064)
			(layers "F.Cu" "F.Mask" "F.Paste")
			(net "JTAG_SCM_PLD_TDO")
		)
		(pad "C7" smd circle
			(at -1.199896 -4.400042 180)
			(size 0.4064 0.4064)
			(layers "F.Cu" "F.Mask" "F.Paste")
			(net "RST_BMC_RSTBTN_OUT_N")
		)
		(pad "C8" smd circle
			(at -0.40005 -4.400042 180)
			(size 0.4064 0.4064)
			(layers "F.Cu" "F.Mask" "F.Paste")
			(net "CLK_25M_OSC_FPGA")
		)
		(pad "C9" smd circle
			(at 0.40005 -4.400042 180)
			(size 0.4064 0.4064)
			(layers "F.Cu" "F.Mask" "F.Paste")
			(net "SMB_BMC_MM16_R3_SDA")
		)
		(pad "C10" smd circle
			(at 1.199896 -4.400042 180)
			(size 0.4064 0.4064)
			(layers "F.Cu" "F.Mask" "F.Paste")
			(net "JTAG_SCM_PLD_R_JTAGEN")
		)
		(pad "C11" smd circle
			(at 1.999996 -4.400042 180)
			(size 0.4064 0.4064)
			(layers "F.Cu" "F.Mask" "F.Paste")
			(net "PWRGD_CPUPWRGD_LVC1")
		)
		(pad "C12" smd circle
			(at 2.800096 -4.400042 180)
			(size 0.4064 0.4064)
			(layers "F.Cu" "F.Mask" "F.Paste")
			(net "SGPIO_PLD_DO_0")
		)
		(pad "C13" smd circle
			(at 3.599942 -4.400042 180)
			(size 0.4064 0.4064)
			(layers "F.Cu" "F.Mask" "F.Paste")
			(net "PU_FPGA_CONFIG_DONE")
		)
		(pad "C14" smd circle
			(at 4.400042 -4.400042 180)
			(size 0.4064 0.4064)
			(layers "F.Cu" "F.Mask" "F.Paste")
			(net "GND")
		)
		(pad "C15" smd circle
			(at 5.199888 -4.400042 180)
			(size 0.4064 0.4064)
			(layers "F.Cu" "F.Mask" "F.Paste")
			(net "VOL_SEN_ALERT_R")
		)
		(pad "C16" smd circle
			(at 5.999988 -4.400042 180)
			(size 0.4064 0.4064)
			(layers "F.Cu" "F.Mask" "F.Paste")
			(net "SMB_BMC_ALERT3_R1_N")
		)
		(pad "D1" smd circle
			(at -5.999988 -3.599942 180)
			(size 0.4064 0.4064)
			(layers "F.Cu" "F.Mask" "F.Paste")
			(net "Net_297")
		)
		(pad "D2" smd circle
			(at -5.199888 -3.599942 180)
			(size 0.4064 0.4064)
			(layers "F.Cu" "F.Mask" "F.Paste")
			(net "Net_303")
		)
		(pad "D3" smd circle
			(at -4.400042 -3.599942 180)
			(size 0.4064 0.4064)
			(layers "F.Cu" "F.Mask" "F.Paste")
			(net "Net_296")
		)
		(pad "D4" smd circle
			(at -3.599942 -3.599942 180)
			(size 0.4064 0.4064)
			(layers "F.Cu" "F.Mask" "F.Paste")
			(net "GND")
		)
		(pad "D5" smd circle
			(at -2.800096 -3.599942 180)
			(size 0.4064 0.4064)
			(layers "F.Cu" "F.Mask" "F.Paste")
			(net "VCCIO0")
		)
		(pad "D6" smd circle
			(at -1.999996 -3.599942 180)
			(size 0.4064 0.4064)
			(layers "F.Cu" "F.Mask" "F.Paste")
			(net "FM_BMC_DBP_PRESENT_N")
		)
		(pad "D7" smd circle
			(at -1.199896 -3.599942 180)
			(size 0.4064 0.4064)
			(layers "F.Cu" "F.Mask" "F.Paste")
			(net "FM_ME_BT_DONE")
		)
		(pad "D8" smd circle
			(at -0.40005 -3.599942 180)
			(size 0.4064 0.4064)
			(layers "F.Cu" "F.Mask" "F.Paste")
			(net "FM_PCH_BMC_THERMTRIP_N")
		)
		(pad "D9" smd circle
			(at 0.40005 -3.599942 180)
			(size 0.4064 0.4064)
			(layers "F.Cu" "F.Mask" "F.Paste")
			(net "Net_246")
		)
		(pad "D10" smd circle
			(at 1.199896 -3.599942 180)
			(size 0.4064 0.4064)
			(layers "F.Cu" "F.Mask" "F.Paste")
			(net "Net_11")
		)
		(pad "D11" smd circle
			(at 1.999996 -3.599942 180)
			(size 0.4064 0.4064)
			(layers "F.Cu" "F.Mask" "F.Paste")
			(net "IRQ_CPU1_VRHOT_N")
		)
		(pad "D12" smd circle
			(at 2.800096 -3.599942 180)
			(size 0.4064 0.4064)
			(layers "F.Cu" "F.Mask" "F.Paste")
			(net "VCCIO0")
		)
		(pad "D13" smd circle
			(at 3.599942 -3.599942 180)
			(size 0.4064 0.4064)
			(layers "F.Cu" "F.Mask" "F.Paste")
			(net "GND")
		)
		(pad "D14" smd circle
			(at 4.400042 -3.599942 180)
			(size 0.4064 0.4064)
			(layers "F.Cu" "F.Mask" "F.Paste")
			(net "H_CPU0_MEMTRIP_LVC1_N")
		)
		(pad "D15" smd circle
			(at 5.199888 -3.599942 180)
			(size 0.4064 0.4064)
			(layers "F.Cu" "F.Mask" "F.Paste")
			(net "SMB_BMC_ALERT4_R1_N")
		)
		(pad "D16" smd circle
			(at 5.999988 -3.599942 180)
			(size 0.4064 0.4064)
			(layers "F.Cu" "F.Mask" "F.Paste")
			(net "H_CPU1_MEMTRIP_LVC1_N")
		)
		(pad "E1" smd circle
			(at -5.999988 -2.800096 180)
			(size 0.4064 0.4064)
			(layers "F.Cu" "F.Mask" "F.Paste")
			(net "Net_304")
		)
		(pad "E2" smd circle
			(at -5.199888 -2.800096 180)
			(size 0.4064 0.4064)
			(layers "F.Cu" "F.Mask" "F.Paste")
			(net "Net_300")
		)
		(pad "E3" smd circle
			(at -4.400042 -2.800096 180)
			(size 0.4064 0.4064)
			(layers "F.Cu" "F.Mask" "F.Paste")
			(net "Net_301")
		)
		(pad "E4" smd circle
			(at -3.599942 -2.800096 180)
			(size 0.4064 0.4064)
			(layers "F.Cu" "F.Mask" "F.Paste")
			(net "VCCIO5")
		)
		(pad "E5" smd circle
			(at -2.800096 -2.800096 180)
			(size 0.4064 0.4064)
			(layers "F.Cu" "F.Mask" "F.Paste")
			(net "GND")
		)
		(pad "E6" smd circle
			(at -1.999996 -2.800096 180)
			(size 0.4064 0.4064)
			(layers "F.Cu" "F.Mask" "F.Paste")
			(net "BMC_CPLD_GPIO_2_R2")
		)
		(pad "E7" smd circle
			(at -1.199896 -2.800096 180)
			(size 0.4064 0.4064)
			(layers "F.Cu" "F.Mask" "F.Paste")
			(net "PWRGD_PCH_PWROK")
		)
		(pad "E8" smd circle
			(at -0.40005 -2.800096 180)
			(size 0.4064 0.4064)
			(layers "F.Cu" "F.Mask" "F.Paste")
			(net "FM_BIOS_POST_CMPLT_BMC_N")
		)
		(pad "E9" smd circle
			(at 0.40005 -2.800096 180)
			(size 0.4064 0.4064)
			(layers "F.Cu" "F.Mask" "F.Paste")
			(net "H_CPU1_PROCHOT_LVC1_R_N")
		)
		(pad "E10" smd circle
			(at 1.199896 -2.800096 180)
			(size 0.4064 0.4064)
			(layers "F.Cu" "F.Mask" "F.Paste")
			(net "FM_CPU_MSMI_CATERR_LVT3_PLD_N")
		)
		(pad "E11" smd circle
			(at 1.999996 -2.800096 180)
			(size 0.4064 0.4064)
			(layers "F.Cu" "F.Mask" "F.Paste")
			(net "TP_PLD_19D")
		)
		(pad "E12" smd circle
			(at 2.800096 -2.800096 180)
			(size 0.4064 0.4064)
			(layers "F.Cu" "F.Mask" "F.Paste")
			(net "GND")
		)
		(pad "E13" smd circle
			(at 3.599942 -2.800096 180)
			(size 0.4064 0.4064)
			(layers "F.Cu" "F.Mask" "F.Paste")
			(net "VCCIO1")
		)
		(pad "E14" smd circle
			(at 4.400042 -2.800096 180)
			(size 0.4064 0.4064)
			(layers "F.Cu" "F.Mask" "F.Paste")
			(net "IRQ_SGPIO_R_N")
		)
		(pad "E15" smd circle
			(at 5.199888 -2.800096 180)
			(size 0.4064 0.4064)
			(layers "F.Cu" "F.Mask" "F.Paste")
			(net "FM_SPD_REMOTE_EN_R")
		)
		(pad "E16" smd circle
			(at 5.999988 -2.800096 180)
			(size 0.4064 0.4064)
			(layers "F.Cu" "F.Mask" "F.Paste")
			(net "RST_SGPIO_RESET_R_N")
		)
		(pad "F1" smd circle
			(at -5.999988 -1.999996 180)
			(size 0.4064 0.4064)
			(layers "F.Cu" "F.Mask" "F.Paste")
			(net "Net_309")
		)
		(pad "F2" smd circle
			(at -5.199888 -1.999996 180)
			(size 0.4064 0.4064)
			(layers "F.Cu" "F.Mask" "F.Paste")
			(net "Net_305")
		)
		(pad "F3" smd circle
			(at -4.400042 -1.999996 180)
			(size 0.4064 0.4064)
			(layers "F.Cu" "F.Mask" "F.Paste")
			(net "Net_308")
		)
		(pad "F4" smd circle
			(at -3.599942 -1.999996 180)
			(size 0.4064 0.4064)
			(layers "F.Cu" "F.Mask" "F.Paste")
			(net "Net_306")
		)
		(pad "F5" smd circle
			(at -2.800096 -1.999996 180)
			(size 0.4064 0.4064)
			(layers "F.Cu" "F.Mask" "F.Paste")
			(net "Net_314")
		)
		(pad "F6" smd circle
			(at -1.999996 -1.999996 180)
			(size 0.4064 0.4064)
			(layers "F.Cu" "F.Mask" "F.Paste")
			(net "GND")
		)
		(pad "F7" smd circle
			(at -1.199896 -1.999996 180)
			(size 0.4064 0.4064)
			(layers "F.Cu" "F.Mask" "F.Paste")
			(net "FM_PCIE_M2_SSD0_PRSNT_N")
		)
		(pad "F8" smd circle
			(at -0.40005 -1.999996 180)
			(size 0.4064 0.4064)
			(layers "F.Cu" "F.Mask" "F.Paste")
			(net "RST_SRST_PLD_BMC_R2_N")
		)
		(pad "F9" smd circle
			(at 0.40005 -1.999996 180)
			(size 0.4064 0.4064)
			(layers "F.Cu" "F.Mask" "F.Paste")
			(net "Net_76")
		)
		(pad "F10" smd circle
			(at 1.199896 -1.999996 180)
			(size 0.4064 0.4064)
			(layers "F.Cu" "F.Mask" "F.Paste")
			(net "IRQ_CPU0_VRHOT_N")
		)
		(pad "F11" smd circle
			(at 1.999996 -1.999996 180)
			(size 0.4064 0.4064)
			(layers "F.Cu" "F.Mask" "F.Paste")
			(net "GND")
		)
		(pad "F12" smd circle
			(at 2.800096 -1.999996 180)
			(size 0.4064 0.4064)
			(layers "F.Cu" "F.Mask" "F.Paste")
			(net "TP_PLD_L3")
		)
		(pad "F13" smd circle
			(at 3.599942 -1.999996 180)
			(size 0.4064 0.4064)
			(layers "F.Cu" "F.Mask" "F.Paste")
			(net "SMB_BMC_ALERT9_R1_N")
		)
		(pad "F14" smd circle
			(at 4.400042 -1.999996 180)
			(size 0.4064 0.4064)
			(layers "F.Cu" "F.Mask" "F.Paste")
			(net "BMC_CPLD_GPIO_8_R2")
		)
		(pad "F15" smd circle
			(at 5.199888 -1.999996 180)
			(size 0.4064 0.4064)
			(layers "F.Cu" "F.Mask" "F.Paste")
			(net "BMC_CPLD_GPIO_7_R2")
		)
		(pad "F16" smd circle
			(at 5.999988 -1.999996 180)
			(size 0.4064 0.4064)
			(layers "F.Cu" "F.Mask" "F.Paste")
			(net "Net_77")
		)
		(pad "G1" smd circle
			(at -5.999988 -1.199896 180)
			(size 0.4064 0.4064)
			(layers "F.Cu" "F.Mask" "F.Paste")
			(net "Net_284")
		)
		(pad "G2" smd circle
			(at -5.199888 -1.199896 180)
			(size 0.4064 0.4064)
			(layers "F.Cu" "F.Mask" "F.Paste")
			(net "Net_312")
		)
		(pad "G3" smd circle
			(at -4.400042 -1.199896 180)
			(size 0.4064 0.4064)
			(layers "F.Cu" "F.Mask" "F.Paste")
			(net "Net_313")
		)
		(pad "G4" smd circle
			(at -3.599942 -1.199896 180)
			(size 0.4064 0.4064)
			(layers "F.Cu" "F.Mask" "F.Paste")
			(net "Net_311")
		)
		(pad "G5" smd circle
			(at -2.800096 -1.199896 180)
			(size 0.4064 0.4064)
			(layers "F.Cu" "F.Mask" "F.Paste")
			(net "Net_310")
		)
		(pad "G6" smd circle
			(at -1.999996 -1.199896 180)
			(size 0.4064 0.4064)
			(layers "F.Cu" "F.Mask" "F.Paste")
			(net "Net_307")
		)
		(pad "G7" smd circle
			(at -1.199896 -1.199896 180)
			(size 0.4064 0.4064)
			(layers "F.Cu" "F.Mask" "F.Paste")
			(net "PVCCA_AUX_PLD")
		)
		(pad "G8" smd circle
			(at -0.40005 -1.199896 180)
			(size 0.4064 0.4064)
			(layers "F.Cu" "F.Mask" "F.Paste")
			(net "VCCIO0")
		)
		(pad "G9" smd circle
			(at 0.40005 -1.199896 180)
			(size 0.4064 0.4064)
			(layers "F.Cu" "F.Mask" "F.Paste")
			(net "VCCIO0")
		)
		(pad "G10" smd circle
			(at 1.199896 -1.199896 180)
			(size 0.4064 0.4064)
			(layers "F.Cu" "F.Mask" "F.Paste")
			(net "PVCCA_AUX_PLD")
		)
		(pad "G11" smd circle
			(at 1.999996 -1.199896 180)
			(size 0.4064 0.4064)
			(layers "F.Cu" "F.Mask" "F.Paste")
			(net "FM_SLPS3_GF_R_N")
		)
		(pad "G12" smd circle
			(at 2.800096 -1.199896 180)
			(size 0.4064 0.4064)
			(layers "F.Cu" "F.Mask" "F.Paste")
			(net "SMB_BMC_ALERT10_R1_N")
		)
		(pad "G13" smd circle
			(at 3.599942 -1.199896 180)
			(size 0.4064 0.4064)
			(layers "F.Cu" "F.Mask" "F.Paste")
			(net "RST_BMC_SELF_HW_R2")
		)
		(pad "G14" smd circle
			(at 4.400042 -1.199896 180)
			(size 0.4064 0.4064)
			(layers "F.Cu" "F.Mask" "F.Paste")
			(net "Net_70")
		)
		(pad "G15" smd circle
			(at 5.199888 -1.199896 180)
			(size 0.4064 0.4064)
			(layers "F.Cu" "F.Mask" "F.Paste")
			(net "Net_69")
		)
		(pad "G16" smd circle
			(at 5.999988 -1.199896 180)
			(size 0.4064 0.4064)
			(layers "F.Cu" "F.Mask" "F.Paste")
			(net "BMC_CPLD_GPIO_12_R2")
		)
	)
)
